(kicad_pcb
	(version 20260206)
	(generator "pcbnew")
	(generator_version "10.0")
	(general
		(thickness 1.6)
		(legacy_teardrops no)
	)
	(paper "A4")
	(title_block
		(title "pdpb — Lightning_PDPB_BRD.brd")
		(comment 1 "Lightning (Wiwynn / Facebook NVMe JBOF) / footprints 1137-1140 of 1140")
	)
	(layers
		(0 "F.Cu" signal "TOP")
		(4 "In1.Cu" signal "L2GND")
		(6 "In2.Cu" signal "L3")
		(8 "In3.Cu" signal "L4VCC")
		(10 "In4.Cu" signal "L5VCC")
		(12 "In5.Cu" signal "L6")
		(14 "In6.Cu" signal "L7GND")
		(2 "B.Cu" signal "BOTTOM")
		(9 "F.Adhes" user "F.Adhesive")
		(11 "B.Adhes" user "B.Adhesive")
		(13 "F.Paste" user "Package Geometry/Pastemask Top")
		(15 "B.Paste" user "Package Geometry/Pastemask Bottom")
		(5 "F.SilkS" user "Ref Des/Silkscreen Top")
		(7 "B.SilkS" user "Ref Des/Silkscreen Bottom")
		(1 "F.Mask" user "Board Geometry/Soldermask Top")
		(3 "B.Mask" user "Board Geometry/Soldermask Bottom")
		(17 "Dwgs.User" user "User.Drawings")
		(19 "Cmts.User" user "User.Comments")
		(21 "Eco1.User" user "User.Eco1")
		(23 "Eco2.User" user "User.Eco2")
		(25 "Edge.Cuts" user "Board Geometry/Outline")
		(27 "Margin" user)
		(31 "F.CrtYd" user "Package Geometry/Place Bound Top")
		(29 "B.CrtYd" user "Package Geometry/Place Bound Bottom")
		(35 "F.Fab" user "Ref Des/Assembly Top")
		(33 "B.Fab" user "Ref Des/Assembly Bottom")
	)
	(footprint ""
		(layer "F.Cu")
		(at 82.931 -435.102 -90)
		(property "Reference" "PR9061"
			(at 0 0 270)
			(layer "F.SilkS")
			(hide yes)
			(effects
				(font
					(size 1.27 1.27)
				)
			)
		)
		(property "Value" "1K4R2F-1-GP"
			(at 0.064008 -3.993896 270)
			(unlocked yes)
			(layer "F.Fab")
			(hide yes)
			(effects
				(font
					(size 1.016 1.016)
					(thickness 0.1524)
				)
			)
		)
		(property "Device Type" "R402H16"
			(at 0.064008 -5.517896 270)
			(unlocked yes)
			(layer "F.Fab")
			(hide yes)
			(effects
				(font
					(size 1.016 1.016)
					(thickness 0.1524)
				)
			)
		)
		(duplicate_pad_numbers_are_jumpers no)
		(fp_line
			(start -0.508 -0.9398)
			(end -0.508 0.9398)
			(stroke
				(width 0.1524)
				(type default)
			)
			(layer "F.SilkS")
		)
		(fp_line
			(start 0.508 -0.9398)
			(end -0.508 -0.9398)
			(stroke
				(width 0.1524)
				(type default)
			)
			(layer "F.SilkS")
		)
		(fp_rect
			(start -0.508 0.9398)
			(end 0.508 -0.9398)
			(stroke
				(width 0)
				(type default)
			)
			(fill no)
			(layer "F.CrtYd")
		)
		(fp_rect
			(start -0.508 0.9398)
			(end 0.508 -0.9398)
			(stroke
				(width 0)
				(type default)
			)
			(fill no)
			(layer "F.Fab")
		)
		(pad "1" smd custom
			(at 0 -0.4445 270)
			(size 0.1397 0.1397)
			(layers "F.Cu" "F.Mask" "F.Paste")
			(net "CLK_BUF_EU1_HIBW_BYPM_LOBW#")
			(options
				(clearance outline)
				(anchor circle)
			)
			(primitives
				(gr_poly
					(pts
						(arc
							(start -0.1778 -0.2794)
							(mid -0.249642 -0.249642)
							(end -0.2794 -0.1778)
						)
						(arc
							(start -0.2794 0.1778)
							(mid -0.249642 0.249642)
							(end -0.1778 0.2794)
						)
						(arc
							(start 0.1778 0.2794)
							(mid 0.249642 0.249642)
							(end 0.2794 0.1778)
						)
						(arc
							(start 0.2794 -0.1778)
							(mid 0.249642 -0.249642)
							(end 0.1778 -0.2794)
						)
					)
					(width 0)
					(fill yes)
				)
			)
		)
		(pad "2" smd custom
			(at 0 0.4445 270)
			(size 0.1397 0.1397)
			(layers "F.Cu" "F.Mask" "F.Paste")
			(net "GND")
			(options
				(clearance outline)
				(anchor circle)
			)
			(primitives
				(gr_poly
					(pts
						(arc
							(start -0.1778 -0.2794)
							(mid -0.249642 -0.249642)
							(end -0.2794 -0.1778)
						)
						(arc
							(start -0.2794 0.1778)
							(mid -0.249642 0.249642)
							(end -0.1778 0.2794)
						)
						(arc
							(start 0.1778 0.2794)
							(mid 0.249642 0.249642)
							(end 0.2794 0.1778)
						)
						(arc
							(start 0.2794 -0.1778)
							(mid 0.249642 -0.249642)
							(end 0.1778 -0.2794)
						)
					)
					(width 0)
					(fill yes)
				)
			)
		)
	)
	(footprint ""
		(layer "F.Cu")
		(at 206.359506 -493.168178 -90)
		(property "Reference" "U9"
			(at 0 0 270)
			(layer "F.SilkS")
			(hide yes)
			(effects
				(font
					(size 1.27 1.27)
				)
			)
		)
		(property "Value" "P2003EVG-GP"
			(at 0 -11.1252 270)
			(unlocked yes)
			(layer "F.Fab")
			(hide yes)
			(effects
				(font
					(size 1.016 1.016)
					(thickness 0.1524)
				)
			)
		)
		(property "Device Type" "SOIC8H79"
			(at 0 -12.6492 270)
			(unlocked yes)
			(layer "F.Fab")
			(hide yes)
			(effects
				(font
					(size 1.016 1.016)
					(thickness 0.1524)
				)
			)
		)
		(duplicate_pad_numbers_are_jumpers no)
		(fp_line
			(start -2.6162 3.429)
			(end -2.6162 1.4732)
			(stroke
				(width 0.4064)
				(type default)
			)
			(layer "F.SilkS")
		)
		(fp_line
			(start -2.7432 1.4224)
			(end 2.1336 1.4224)
			(stroke
				(width 0.1524)
				(type default)
			)
			(layer "F.SilkS")
		)
		(fp_line
			(start 2.1336 1.4224)
			(end 2.1336 -1.4224)
			(stroke
				(width 0.1524)
				(type default)
			)
			(layer "F.SilkS")
		)
		(fp_line
			(start -2.2352 0)
			(end -2.7432 0.508)
			(stroke
				(width 0.1524)
				(type default)
			)
			(layer "F.SilkS")
		)
		(fp_line
			(start -2.7432 -0.508)
			(end -2.2352 0)
			(stroke
				(width 0.1524)
				(type default)
			)
			(layer "F.SilkS")
		)
		(fp_line
			(start -2.7432 -1.4224)
			(end -2.7432 1.4224)
			(stroke
				(width 0.1524)
				(type default)
			)
			(layer "F.SilkS")
		)
		(fp_line
			(start 2.1336 -1.4224)
			(end -2.7432 -1.4224)
			(stroke
				(width 0.1524)
				(type default)
			)
			(layer "F.SilkS")
		)
		(fp_poly
			(pts
				(xy 2.2098 -1.4224) (xy 2.2098 1.4224) (xy -2.2225 1.4224) (xy -2.2225 -1.4224)
			)
			(stroke
				(width 0)
				(type default)
			)
			(fill yes)
			(layer "F.SilkS")
		)
		(fp_rect
			(start -2.4511 2.9972)
			(end 2.4511 -2.9972)
			(stroke
				(width 0)
				(type default)
			)
			(fill no)
			(layer "F.CrtYd")
		)
		(fp_poly
			(pts
				(xy -2.8194 3.6322) (xy -2.8194 -3.6322) (xy 2.8194 -3.6322) (xy 2.8194 -2.2987) (xy 2.4511 -2.2987)
				(xy 2.4511 -2.9972) (xy -2.4511 -2.9972) (xy -2.4511 2.9972) (xy 2.4511 2.9972) (xy 2.4511 -2.286)
				(xy 2.8194 -2.286) (xy 2.8194 3.6322)
			)
			(stroke
				(width 0)
				(type default)
			)
			(fill no)
			(layer "F.CrtYd")
		)
		(fp_rect
			(start -2.8194 3.6322)
			(end 2.8194 -3.6322)
			(stroke
				(width 0)
				(type default)
			)
			(fill no)
			(layer "F.Fab")
		)
		(pad "1" smd rect
			(at -1.905 2.54 270)
			(size 0.635 1.651)
			(layers "F.Cu" "F.Mask" "F.Paste")
			(net "P12V")
		)
		(pad "2" smd rect
			(at -0.635 2.54 270)
			(size 0.635 1.651)
			(layers "F.Cu" "F.Mask" "F.Paste")
			(net "P12V")
		)
		(pad "3" smd rect
			(at 0.635 2.54 270)
			(size 0.635 1.651)
			(layers "F.Cu" "F.Mask" "F.Paste")
			(net "P12V")
		)
		(pad "4" smd rect
			(at 1.905 2.54 270)
			(size 0.635 1.651)
			(layers "F.Cu" "F.Mask" "F.Paste")
			(net "SW_SSD0_N")
		)
		(pad "5" smd rect
			(at 1.905 -2.54 270)
			(size 0.635 1.651)
			(layers "F.Cu" "F.Mask" "F.Paste")
			(net "P12V_SSD0")
		)
		(pad "6" smd rect
			(at 0.635 -2.54 270)
			(size 0.635 1.651)
			(layers "F.Cu" "F.Mask" "F.Paste")
			(net "P12V_SSD0")
		)
		(pad "7" smd rect
			(at -0.635 -2.54 270)
			(size 0.635 1.651)
			(layers "F.Cu" "F.Mask" "F.Paste")
			(net "P12V_SSD0")
		)
		(pad "8" smd rect
			(at -1.905 -2.54 270)
			(size 0.635 1.651)
			(layers "F.Cu" "F.Mask" "F.Paste")
			(net "P12V_SSD0")
		)
	)
	(footprint ""
		(layer "F.Cu")
		(at 25.3238 -293.2176)
		(property "Reference" "C389"
			(at 0 0 0)
			(layer "F.SilkS")
			(hide yes)
			(effects
				(font
					(size 1.27 1.27)
				)
			)
		)
		(property "Value" "SCD1U25V2KX-2-GP"
			(at 1.1811 -2.7051 0)
			(unlocked yes)
			(layer "F.Fab")
			(hide yes)
			(effects
				(font
					(size 1.016 1.016)
					(thickness 0.1524)
				)
			)
		)
		(property "Device Type" "C402H22"
			(at 1.1811 -4.2291 0)
			(unlocked yes)
			(layer "F.Fab")
			(hide yes)
			(effects
				(font
					(size 1.016 1.016)
					(thickness 0.1524)
				)
			)
		)
		(duplicate_pad_numbers_are_jumpers no)
		(fp_rect
			(start -0.4318 0.9525)
			(end 0.4318 -0.9525)
			(stroke
				(width 0)
				(type default)
			)
			(fill no)
			(layer "F.CrtYd")
		)
		(fp_rect
			(start -0.4318 0.9525)
			(end 0.4318 -0.9525)
			(stroke
				(width 0)
				(type default)
			)
			(fill no)
			(layer "F.Fab")
		)
		(pad "1" smd custom
			(at 0 -0.4445)
			(size 0.1524 0.1524)
			(layers "F.Cu" "F.Mask" "F.Paste")
			(net "P12V")
			(options
				(clearance outline)
				(anchor circle)
			)
			(primitives
				(gr_poly
					(pts
						(arc
							(start 0.3048 -0.2032)
							(mid 0.275042 -0.275042)
							(end 0.2032 -0.3048)
						)
						(arc
							(start -0.2032 -0.3048)
							(mid -0.275042 -0.275042)
							(end -0.3048 -0.2032)
						)
						(arc
							(start -0.3048 0.2032)
							(mid -0.275042 0.275042)
							(end -0.2032 0.3048)
						)
						(arc
							(start 0.2032 0.3048)
							(mid 0.275042 0.275042)
							(end 0.3048 0.2032)
						)
					)
					(width 0)
					(fill yes)
				)
			)
		)
		(pad "2" smd custom
			(at 0 0.4445)
			(size 0.1524 0.1524)
			(layers "F.Cu" "F.Mask" "F.Paste")
			(net "SW_SSD7_N")
			(options
				(clearance outline)
				(anchor circle)
			)
			(primitives
				(gr_poly
					(pts
						(arc
							(start 0.3048 -0.2032)
							(mid 0.275042 -0.275042)
							(end 0.2032 -0.3048)
						)
						(arc
							(start -0.2032 -0.3048)
							(mid -0.275042 -0.275042)
							(end -0.3048 -0.2032)
						)
						(arc
							(start -0.3048 0.2032)
							(mid -0.275042 0.275042)
							(end -0.2032 0.3048)
						)
						(arc
							(start 0.2032 0.3048)
							(mid 0.275042 0.275042)
							(end 0.3048 0.2032)
						)
					)
					(width 0)
					(fill yes)
				)
			)
		)
	)
	(footprint ""
		(layer "F.Cu")
		(at 90.17 -224.282)
		(property "Reference" "R9613"
			(at 0 0 0)
			(layer "F.SilkS")
			(hide yes)
			(effects
				(font
					(size 1.27 1.27)
				)
			)
		)
		(property "Value" "10R2F-L-GP"
			(at 0.064008 -3.993896 0)
			(unlocked yes)
			(layer "F.Fab")
			(hide yes)
			(effects
				(font
					(size 1.016 1.016)
					(thickness 0.1524)
				)
			)
		)
		(property "Device Type" "R402H14"
			(at 0.064008 -5.517896 0)
			(unlocked yes)
			(layer "F.Fab")
			(hide yes)
			(effects
				(font
					(size 1.016 1.016)
					(thickness 0.1524)
				)
			)
		)
		(duplicate_pad_numbers_are_jumpers no)
		(fp_line
			(start -0.508 -0.9398)
			(end -0.508 0.9398)
			(stroke
				(width 0.1524)
				(type default)
			)
			(layer "F.SilkS")
		)
		(fp_line
			(start 0.508 -0.9398)
			(end -0.508 -0.9398)
			(stroke
				(width 0.1524)
				(type default)
			)
			(layer "F.SilkS")
		)
		(fp_rect
			(start -0.508 0.9398)
			(end 0.508 -0.9398)
			(stroke
				(width 0)
				(type default)
			)
			(fill no)
			(layer "F.CrtYd")
		)
		(fp_rect
			(start -0.508 0.9398)
			(end 0.508 -0.9398)
			(stroke
				(width 0)
				(type default)
			)
			(fill no)
			(layer "F.Fab")
		)
		(pad "1" smd custom
			(at 0 -0.4445)
			(size 0.1397 0.1397)
			(layers "F.Cu" "F.Mask" "F.Paste")
			(net "SSD_PRSNT_NET12")
			(options
				(clearance outline)
				(anchor circle)
			)
			(primitives
				(gr_poly
					(pts
						(arc
							(start -0.1778 -0.2794)
							(mid -0.249642 -0.249642)
							(end -0.2794 -0.1778)
						)
						(arc
							(start -0.2794 0.1778)
							(mid -0.249642 0.249642)
							(end -0.1778 0.2794)
						)
						(arc
							(start 0.1778 0.2794)
							(mid 0.249642 0.249642)
							(end 0.2794 0.1778)
						)
						(arc
							(start 0.2794 -0.1778)
							(mid 0.249642 -0.249642)
							(end 0.1778 -0.2794)
						)
					)
					(width 0)
					(fill yes)
				)
			)
		)
		(pad "2" smd custom
			(at 0 0.4445)
			(size 0.1397 0.1397)
			(layers "F.Cu" "F.Mask" "F.Paste")
			(net "SSD_PRSNT12")
			(options
				(clearance outline)
				(anchor circle)
			)
			(primitives
				(gr_poly
					(pts
						(arc
							(start -0.1778 -0.2794)
							(mid -0.249642 -0.249642)
							(end -0.2794 -0.1778)
						)
						(arc
							(start -0.2794 0.1778)
							(mid -0.249642 0.249642)
							(end -0.1778 0.2794)
						)
						(arc
							(start 0.1778 0.2794)
							(mid 0.249642 0.249642)
							(end 0.2794 0.1778)
						)
						(arc
							(start 0.2794 -0.1778)
							(mid 0.249642 -0.249642)
							(end 0.1778 -0.2794)
						)
					)
					(width 0)
					(fill yes)
				)
			)
		)
	)
)
